FILE_TYPE = CONNECTIVITY;
{Allegro Design Entry HDL 17.4-2019 S026 (4007227) 1/17/2022}
"PAGE_NUMBER" = 111;
0"NC";
1"GND\g";
2"GND\g";
3"GND\g";
4"GND\g";
5"GND\g";
6"GND\g";
7"GND\g";
8"GND\g";
9"GND\g";
10"P3V3_AUX\g";
11"GND\g";
12"P3V3_AUX\g";
13"GND\g";
14"P3V3_AUX\g";
15"P3V3_AUX\g";
16"FM_P2E_BUF2_VOD_SEL";
17"FM_P2E_BUF2_SD_TH";
18"FM_P2E_BUF2_RXDET";
19"FM_P2E_BUF2_EQA1";
20"FM_P2E_BUF2_EQA0";
21"P3V3_AUX\g";
22"P3V3_AUX\g";
23"GND\g";
24"P3V3_AUX\g";
25"P2E_MB_BMC_RX_BUF2_C_DN<0>";
26"P2E_MB_BMC_RX_BUF2_C_DP<0>";
27"P2E_MB_BMC_TX_BUF2_DN<0>";
28"P2E_MB_BMC_TX_BUF2_DP<0>";
29"FM_P2E_BUF2_RXDET";
30"FM_P2E_EN2_N";
31"FM_P2E_BUF2_VODA_DB";
32"FM_P2E_BUF2_VODB_DB";
33"FM_P2E_BUF2_EQB0";
34"FM_P2E_BUF2_EQB1";
35"CLK_GEN2_GPU_FPGA_OE_OR_N";
36"FM_P2E_BUF2_EQA0";
37"FM_P2E_BUF2_EQA1";
38"FM_P2E_BUF2_EQB1";
39"FM_P2E_BUF2_EQB0";
40"FM_P2E_BUF2_VODB_DB";
41"P2E_MB_BMC_TX_C_R2_DP<0>";
42"P2E_MB_BMC_TX_C_R2_DN<0>";
43"FM_P2E_BUF2_VODA_DB";
44"PD_P2E_BUF2_ENSMB";
45"FM_P2E_BUF2_SD_TH";
46"P2E_MB_BMC_RX_R2_DP<0>";
47"P2E_MB_BMC_RX_R2_DN<0>";
48"BUF2_VDD";
49"NC_RES";
50"FM_P2E_BUF2_VOD_SEL";
%"DS125BR111RTWR"
"1","(-4725,5325)","0","pure_quanta","I1";
;
LOCATION"U6000"
SEC"1"
ROOM"PCIE REDRIVER BOM2"
PART_TYPE"SMLF"
VALUE"DS125BR111RTWR"
MATERIAL"IC"
SEC_TYPE""
CDS_LIB"pure_quanta"
NEEDS_NO_SIZE"TRUE"
CDS_LMAN_SYM_OUTLINE"-375,700,375,-700"
PART_NUMBER"AL000125003";
"TH_GND"
$PN"25"2;
"INA+"
$PN"24"41;
"INA-"
$PN"23"42;
"VDD_22"
$PN"22"48;
"VDD_21"
$PN"21"48;
"OUTB+"
$PN"20"26;
"OUTB-"
$PN"19"25;
"RXDET||DONE#"
$PN"18"29;
"VOD_SEL||READEN#"
$PN"17"50;
"VDD_SEL"
$PN"16"23;
"VIN"
$PN"15"15;
"SD_TH"
$PN"14"45;
"RES"
$PN"13"49;
"INB-"
$PN"12"47;
"INB+"
$PN"11"46;
"EQA0||AD0"
$PN"10"36;
"EQA1||AD1"
$PN"9"37;
"OUTA-"
$PN"8"27;
"OUTA+"
$PN"7"28;
"PWDN"
$PN"6"30;
"SCL||VODB_DB"
$PN"5"40;
"SDA||VODA_DB"
$PN"4"43;
"ENSMB"
$PN"3"44;
"EQB1||AD2"
$PN"2"38;
"EQB0||AD3"
$PN"1"39;
%"Q_RES"
"2","(-7525,4875)","0","pure_quanta","I12";
;
LOCATION"R6160"
$SEC"1"
CDS_SEC"1"
WATTAGE"1/16W"
VALUE"1K"
MATERIAL"CHIP"
PACK_TYPE"0402LF"
TOLERANCE"1%"
ROOM"PCIE REDRIVER BOM2"
CDS_LIB"pure_quanta"
PART_NUMBER"CS21002FB06";
"A"
$PN"1"44;
"B"
$PN"2"1;
%"UNIVERSAL_GND"
"1","(-7525,4575)","0","pure_quanta_power","I13";
;
CDS_LIB"pure_quanta_power"
HDL_POWER"GND";
"A"1;
%"UNIVERSAL_POWER"
"1","(-6125,6425)","0","pure_quanta_power","I2";
;
HDL_POWER"P3V3_AUX"
CDS_LIB"pure_quanta_power";
"A"15;
%"Q_RES"
"1","(-3275,5225)","0","pure_quanta","I23";
;
LOCATION"R6162"
$SEC"1"
CDS_SEC"1"
MATERIAL"CHIP"
WATTAGE"1/16W"
ROOM"PCIE REDRIVER BOM2"
PACK_TYPE"0402LF"
TOLERANCE"5%"
VALUE"0"
CDS_LIB"pure_quanta"
PART_NUMBER"CS00002JB13";
"B"
$PN"2"35;
"A"
$PN"1"30;
%"UNIVERSAL_GND"
"1","(-4000,4500)","0","pure_quanta_power","I29";
;
CDS_LIB"pure_quanta_power"
HDL_POWER"GND";
"A"2;
%"Q_CAP"
"1","(-7725,6075)","0","pure_quanta","I3";
;
LOCATION"C6009"
$SEC"1"
CDS_SEC"1"
ROOM"PCIE REDRIVER BOM2"
TOLERANCE"10%"
VALUE"1UF"
PACK_TYPE"C0402"
MATERIAL"X6S"
VOLTAGE"25V"
CDS_LIB"pure_quanta"
PART_NUMBER"CH5104KEB02";
"B"
$PN"2"23;
"A"
$PN"1"15;
%"UNIVERSAL_POWER"
"1","(-7000,3800)","0","pure_quanta_power","I30";
;
HDL_POWER"P3V3_AUX"
CDS_LIB"pure_quanta_power";
"A"24;
%"Q_RES"
"2","(-7000,2850)","0","pure_quanta","I32";
;
LOCATION"R6164"
$SEC"1"
CDS_SEC"1"
ROOM"PCIE REDRIVER BOM2"
TOLERANCE"1%"
VALUE"1K"
MATERIAL"CHIP"
WATTAGE"1/16W"
PACK_TYPE"0402LF"
CDS_LIB"pure_quanta"
PART_NUMBER"CS21002FB06";
"A"
$PN"1"34;
"B"
$PN"2"3;
%"UNIVERSAL_GND"
"1","(-7000,2400)","0","pure_quanta_power","I35";
;
CDS_LIB"pure_quanta_power"
HDL_POWER"GND";
"A"3;
%"UNIVERSAL_GND"
"1","(-6550,2400)","0","pure_quanta_power","I36";
;
CDS_LIB"pure_quanta_power"
HDL_POWER"GND";
"A"4;
%"Q_RES"
"2","(-7000,3425)","0","pure_quanta","I39";
;
LOCATION"R6163"
$SEC"1"
CDS_SEC"1"
VALUE"1K"
TOLERANCE"1%"
PACK_TYPE"0402LF"
MATERIAL"EMPTY"
WATTAGE"1/16W"
ROOM"PCIE REDRIVER BOM2"
CDS_LIB"pure_quanta"
PART_NUMBER"CS21002FB06";
"A"
$PN"1"24;
"B"
$PN"2"34;
%"UNIVERSAL_GND"
"1","(-6675,5650)","0","pure_quanta_power","I4";
;
CDS_LIB"pure_quanta_power"
HDL_POWER"GND";
"A"23;
%"Q_RES"
"2","(-6550,2850)","0","pure_quanta","I40";
;
LOCATION"R6166"
$SEC"1"
CDS_SEC"1"
PACK_TYPE"0402LF"
MATERIAL"EMPTY"
VALUE"1K"
TOLERANCE"1%"
WATTAGE"1/16W"
ROOM"PCIE REDRIVER BOM2"
CDS_LIB"pure_quanta"
PART_NUMBER"CS21002FB06";
"A"
$PN"1"33;
"B"
$PN"2"4;
%"Q_RES"
"2","(-6550,3425)","0","pure_quanta","I41";
;
LOCATION"R6165"
$SEC"1"
CDS_SEC"1"
ROOM"PCIE REDRIVER BOM2"
WATTAGE"1/16W"
MATERIAL"EMPTY"
TOLERANCE"1%"
VALUE"1K"
PACK_TYPE"0402LF"
CDS_LIB"pure_quanta"
PART_NUMBER"CS21002FB06";
"A"
$PN"1"24;
"B"
$PN"2"33;
%"Q_RES"
"2","(-4625,3425)","0","pure_quanta","I44";
;
LOCATION"R6173"
$SEC"1"
CDS_SEC"1"
WATTAGE"1/16W"
MATERIAL"EMPTY"
PACK_TYPE"0402LF"
TOLERANCE"1%"
VALUE"1K"
ROOM"PCIE REDRIVER BOM2"
CDS_LIB"pure_quanta"
PART_NUMBER"CS21002FB06";
"A"
$PN"1"22;
"B"
$PN"2"20;
%"Q_RES"
"2","(-4625,2850)","0","pure_quanta","I45";
;
LOCATION"R6174"
$SEC"1"
CDS_SEC"1"
PACK_TYPE"0402LF"
TOLERANCE"1%"
WATTAGE"1/16W"
MATERIAL"EMPTY"
VALUE"1K"
ROOM"PCIE REDRIVER BOM2"
CDS_LIB"pure_quanta"
PART_NUMBER"CS21002FB06";
"A"
$PN"1"20;
"B"
$PN"2"5;
%"UNIVERSAL_GND"
"1","(-4625,2400)","0","pure_quanta_power","I46";
;
CDS_LIB"pure_quanta_power"
HDL_POWER"GND";
"A"5;
%"UNIVERSAL_POWER"
"1","(-5075,3800)","0","pure_quanta_power","I47";
;
HDL_POWER"P3V3_AUX"
CDS_LIB"pure_quanta_power";
"A"22;
%"Q_RES"
"2","(-5075,3425)","0","pure_quanta","I48";
;
LOCATION"R6171"
$SEC"1"
CDS_SEC"1"
ROOM"PCIE REDRIVER BOM2"
PACK_TYPE"0402LF"
WATTAGE"1/16W"
TOLERANCE"1%"
VALUE"1K"
MATERIAL"EMPTY"
CDS_LIB"pure_quanta"
PART_NUMBER"CS21002FB06";
"A"
$PN"1"22;
"B"
$PN"2"19;
%"Q_RES"
"2","(-5075,2850)","0","pure_quanta","I49";
;
LOCATION"R6172"
$SEC"1"
CDS_SEC"1"
ROOM"PCIE REDRIVER BOM2"
WATTAGE"1/16W"
VALUE"1K"
PACK_TYPE"0402LF"
MATERIAL"CHIP"
TOLERANCE"1%"
CDS_LIB"pure_quanta"
PART_NUMBER"CS21002FB06";
"A"
$PN"1"19;
"B"
$PN"2"6;
%"Q_CAP"
"1","(-7150,6075)","0","pure_quanta","I5";
;
LOCATION"C6010"
$SEC"1"
CDS_SEC"1"
TOLERANCE"10%"
ROOM"PCIE REDRIVER BOM2"
VALUE"10UF"
PACK_TYPE"C0805"
MATERIAL"X6S"
VOLTAGE"16V"
CDS_LIB"pure_quanta"
PART_NUMBER"CH6103KEA00";
"B"
$PN"2"23;
"A"
$PN"1"15;
%"UNIVERSAL_GND"
"1","(-5075,2400)","0","pure_quanta_power","I50";
;
CDS_LIB"pure_quanta_power"
HDL_POWER"GND";
"A"6;
%"Q_RES"
"2","(-6525,1725)","0","pure_quanta","I53";
;
LOCATION"R6169"
$SEC"1"
CDS_SEC"1"
PACK_TYPE"0402LF"
MATERIAL"EMPTY"
WATTAGE"1/16W"
TOLERANCE"1%"
VALUE"1K"
ROOM"PCIE REDRIVER BOM2"
CDS_LIB"pure_quanta"
PART_NUMBER"CS21002FB06";
"A"
$PN"1"21;
"B"
$PN"2"31;
%"UNIVERSAL_GND"
"1","(-6525,700)","0","pure_quanta_power","I55";
;
CDS_LIB"pure_quanta_power"
HDL_POWER"GND";
"A"7;
%"UNIVERSAL_POWER"
"1","(-6975,2100)","0","pure_quanta_power","I56";
;
HDL_POWER"P3V3_AUX"
CDS_LIB"pure_quanta_power";
"A"21;
%"Q_RES"
"2","(-6975,1725)","0","pure_quanta","I57";
;
LOCATION"R6167"
$SEC"1"
CDS_SEC"1"
VALUE"1K"
TOLERANCE"1%"
WATTAGE"1/16W"
MATERIAL"EMPTY"
PACK_TYPE"0402LF"
ROOM"PCIE REDRIVER BOM2"
CDS_LIB"pure_quanta"
PART_NUMBER"CS21002FB06";
"A"
$PN"1"21;
"B"
$PN"2"32;
%"Q_RES"
"2","(-6975,1150)","0","pure_quanta","I58";
;
LOCATION"R6168"
$SEC"1"
CDS_SEC"1"
ROOM"PCIE REDRIVER BOM2"
PACK_TYPE"0402LF"
MATERIAL"CHIP"
WATTAGE"1/16W"
VALUE"1K"
TOLERANCE"1%"
CDS_LIB"pure_quanta"
PART_NUMBER"CS21002FB06";
"A"
$PN"1"32;
"B"
$PN"2"8;
%"UNIVERSAL_GND"
"1","(-6975,700)","0","pure_quanta_power","I59";
;
CDS_LIB"pure_quanta_power"
HDL_POWER"GND";
"A"8;
%"Q_CAP"
"1","(-6575,6025)","0","pure_quanta","I6";
;
LOCATION"C6011"
$SEC"1"
CDS_SEC"1"
PACK_TYPE"0402"
TOLERANCE"10%"
MATERIAL"X7R"
VOLTAGE"25V"
VALUE"0.1UF"
ROOM"PCIE REDRIVER BOM2"
CDS_LIB"pure_quanta"
PART_NUMBER"CH4104K1B00";
"B"
$PN"2"23;
"A"
$PN"1"48;
%"Q_RES"
"2","(-6525,1150)","0","pure_quanta","I60";
;
LOCATION"R6170"
$SEC"1"
CDS_SEC"1"
PACK_TYPE"0402LF"
VALUE"1K"
TOLERANCE"1%"
MATERIAL"CHIP"
WATTAGE"1/16W"
ROOM"PCIE REDRIVER BOM2"
CDS_LIB"pure_quanta"
PART_NUMBER"CS21002FB06";
"A"
$PN"1"31;
"B"
$PN"2"7;
%"Q_RES"
"2","(-4825,1625)","0","pure_quanta","I63";
;
LOCATION"R6175"
$SEC"1"
CDS_SEC"1"
PACK_TYPE"0402LF"
MATERIAL"EMPTY"
TOLERANCE"1%"
WATTAGE"1/16W"
VALUE"1K"
ROOM"PCIE REDRIVER BOM2"
CDS_LIB"pure_quanta"
PART_NUMBER"CS21002FB06";
"A"
$PN"1"10;
"B"
$PN"2"18;
%"Q_RES"
"2","(-4825,1050)","0","pure_quanta","I64";
;
LOCATION"R6176"
$SEC"1"
CDS_SEC"1"
PACK_TYPE"0402LF"
MATERIAL"EMPTY"
TOLERANCE"1%"
WATTAGE"1/16W"
VALUE"1K"
ROOM"PCIE REDRIVER BOM2"
CDS_LIB"pure_quanta"
PART_NUMBER"CS21002FB06";
"A"
$PN"1"18;
"B"
$PN"2"9;
%"UNIVERSAL_GND"
"1","(-4825,600)","0","pure_quanta_power","I65";
;
CDS_LIB"pure_quanta_power"
HDL_POWER"GND";
"A"9;
%"UNIVERSAL_POWER"
"1","(-4825,1950)","0","pure_quanta_power","I66";
;
HDL_POWER"P3V3_AUX"
CDS_LIB"pure_quanta_power";
"A"10;
%"UNIVERSAL_GND"
"1","(-3475,625)","0","pure_quanta_power","I67";
;
CDS_LIB"pure_quanta_power"
HDL_POWER"GND";
"A"11;
%"Q_RES"
"2","(-3475,1075)","0","pure_quanta","I68";
;
LOCATION"R6178"
$SEC"1"
CDS_SEC"1"
VALUE"1K"
MATERIAL"EMPTY"
WATTAGE"1/16W"
PACK_TYPE"0402LF"
TOLERANCE"1%"
ROOM"PCIE REDRIVER BOM2"
CDS_LIB"pure_quanta"
PART_NUMBER"CS21002FB06";
"A"
$PN"1"17;
"B"
$PN"2"11;
%"Q_CAP"
"1","(-6025,6025)","0","pure_quanta","I7";
;
LOCATION"C6012"
$SEC"1"
CDS_SEC"1"
VALUE"0.1UF"
VOLTAGE"25V"
TOLERANCE"10%"
PACK_TYPE"0402"
MATERIAL"X7R"
ROOM"PCIE REDRIVER BOM2"
CDS_LIB"pure_quanta"
PART_NUMBER"CH4104K1B00";
"B"
$PN"2"23;
"A"
$PN"1"48;
%"UNIVERSAL_POWER"
"1","(-3475,1975)","0","pure_quanta_power","I70";
;
HDL_POWER"P3V3_AUX"
CDS_LIB"pure_quanta_power";
"A"12;
%"UNIVERSAL_GND"
"1","(-2125,600)","0","pure_quanta_power","I72";
;
CDS_LIB"pure_quanta_power"
HDL_POWER"GND";
"A"13;
%"Q_RES"
"2","(-2125,1050)","0","pure_quanta","I73";
;
LOCATION"R6180"
$SEC"1"
CDS_SEC"1"
PACK_TYPE"0402LF"
VALUE"1K"
MATERIAL"EMPTY"
TOLERANCE"1%"
WATTAGE"1/16W"
ROOM"PCIE REDRIVER BOM2"
CDS_LIB"pure_quanta"
PART_NUMBER"CS21002FB06";
"A"
$PN"1"16;
"B"
$PN"2"13;
%"UNIVERSAL_POWER"
"1","(-2125,1950)","0","pure_quanta_power","I75";
;
HDL_POWER"P3V3_AUX"
CDS_LIB"pure_quanta_power";
"A"14;
%"Q_RES"
"2","(-3475,1650)","0","pure_quanta","I77";
;
LOCATION"R6177"
$SEC"1"
CDS_SEC"1"
MATERIAL"CHIP"
PACK_TYPE"0402LF"
TOLERANCE"1%"
VALUE"1K"
WATTAGE"1/16W"
ROOM"PCIE REDRIVER BOM2"
CDS_LIB"pure_quanta"
PART_NUMBER"CS21002FB06";
"A"
$PN"1"12;
"B"
$PN"2"17;
%"Q_RES"
"2","(-2125,1625)","0","pure_quanta","I78";
;
LOCATION"R6179"
$SEC"1"
CDS_SEC"1"
MATERIAL"CHIP"
TOLERANCE"1%"
VALUE"1K"
WATTAGE"1/16W"
PACK_TYPE"0402LF"
ROOM"PCIE REDRIVER BOM2"
CDS_LIB"pure_quanta"
PART_NUMBER"CS21002FB06";
"A"
$PN"1"14;
"B"
$PN"2"16;
END.
